(kicad_pcb
	(version 20260206)
	(generator "pcbnew")
	(generator_version "10.0")
	(general
		(thickness 1.6)
		(legacy_teardrops no)
	)
	(paper "A4")
	(title_block
		(title "03242023_DA0F0TMBIJ0_F0T_Motherboard_J_brd_V01_OCP.brd")
		(comment 1 "Grand Teton / footprints 409-415 of 6105")
	)
	(layers
		(0 "F.Cu" signal "TOP")
		(4 "In1.Cu" signal "GND")
		(6 "In2.Cu" signal "IN1")
		(8 "In3.Cu" signal "GND1")
		(10 "In4.Cu" signal "IN2")
		(12 "In5.Cu" signal "GND2")
		(14 "In6.Cu" signal "IN3")
		(16 "In7.Cu" signal "GND3")
		(18 "In8.Cu" signal "VCC")
		(20 "In9.Cu" signal "VCC1")
		(22 "In10.Cu" signal "GND4")
		(24 "In11.Cu" signal "IN4")
		(26 "In12.Cu" signal "GND5")
		(28 "In13.Cu" signal "IN5")
		(30 "In14.Cu" signal "GND6")
		(32 "In15.Cu" signal "IN6")
		(34 "In16.Cu" signal "GND7")
		(2 "B.Cu" signal "BOTTOM")
		(9 "F.Adhes" user "F.Adhesive")
		(11 "B.Adhes" user "B.Adhesive")
		(13 "F.Paste" user "Package Geometry/Pastemask Top")
		(15 "B.Paste" user "Package Geometry/Pastemask Bottom")
		(5 "F.SilkS" user "Ref Des/Silkscreen Top")
		(7 "B.SilkS" user "Ref Des/Silkscreen Bottom")
		(1 "F.Mask" user "Board Geometry/Soldermask Top")
		(3 "B.Mask" user "Board Geometry/Soldermask Bottom")
		(17 "Dwgs.User" user "User.Drawings")
		(19 "Cmts.User" user "User.Comments")
		(21 "Eco1.User" user "User.Eco1")
		(23 "Eco2.User" user "User.Eco2")
		(25 "Edge.Cuts" user "Board Geometry/Outline")
		(27 "Margin" user)
		(31 "F.CrtYd" user "Package Geometry/Place Bound Top")
		(29 "B.CrtYd" user "Package Geometry/Place Bound Bottom")
		(35 "F.Fab" user "Ref Des/Assembly Top")
		(33 "B.Fab" user "Ref Des/Assembly Bottom")
	)
	(footprint ""
		(layer "F.Cu")
		(at 383.514854 -73.15962)
		(property "Reference" "PC1642"
			(at 0 0 0)
			(layer "F.SilkS")
			(hide yes)
			(effects
				(font
					(size 1.27 1.27)
				)
			)
		)
		(property "Value" ""
			(at 0 0 0)
			(layer "F.Fab")
			(effects
				(font
					(size 1.27 1.27)
				)
			)
		)
		(duplicate_pad_numbers_are_jumpers no)
		(fp_line
			(start -0.7874 -0.4064)
			(end 0.7874 -0.4064)
			(stroke
				(width 0.1524)
				(type default)
			)
			(layer "F.SilkS")
		)
		(fp_line
			(start -0.7874 0.4064)
			(end -0.7874 -0.4064)
			(stroke
				(width 0.1524)
				(type default)
			)
			(layer "F.SilkS")
		)
		(fp_line
			(start 0.7874 -0.4064)
			(end 0.7874 0.4064)
			(stroke
				(width 0.1524)
				(type default)
			)
			(layer "F.SilkS")
		)
		(fp_line
			(start 0.7874 0.4064)
			(end -0.7874 0.4064)
			(stroke
				(width 0.1524)
				(type default)
			)
			(layer "F.SilkS")
		)
		(fp_line
			(start -0.67945 -0.305054)
			(end -0.12065 -0.305054)
			(stroke
				(width 0.1)
				(type default)
			)
			(layer "F.Fab")
		)
		(fp_line
			(start -0.67945 0.3048)
			(end -0.67945 -0.305054)
			(stroke
				(width 0.1)
				(type default)
			)
			(layer "F.Fab")
		)
		(fp_line
			(start -0.12065 -0.305054)
			(end -0.12065 -0.2794)
			(stroke
				(width 0.1)
				(type default)
			)
			(layer "F.Fab")
		)
		(fp_line
			(start -0.12065 -0.2794)
			(end 0.12065 -0.2794)
			(stroke
				(width 0.1)
				(type default)
			)
			(layer "F.Fab")
		)
		(fp_line
			(start -0.12065 0.2794)
			(end -0.12065 0.3048)
			(stroke
				(width 0.1)
				(type default)
			)
			(layer "F.Fab")
		)
		(fp_line
			(start -0.12065 0.3048)
			(end -0.67945 0.3048)
			(stroke
				(width 0.1)
				(type default)
			)
			(layer "F.Fab")
		)
		(fp_line
			(start 0.120396 0.2794)
			(end -0.12065 0.2794)
			(stroke
				(width 0.1)
				(type default)
			)
			(layer "F.Fab")
		)
		(fp_line
			(start 0.120396 0.3048)
			(end 0.120396 0.2794)
			(stroke
				(width 0.1)
				(type default)
			)
			(layer "F.Fab")
		)
		(fp_line
			(start 0.12065 -0.3048)
			(end 0.67945 -0.3048)
			(stroke
				(width 0.1)
				(type default)
			)
			(layer "F.Fab")
		)
		(fp_line
			(start 0.12065 -0.2794)
			(end 0.12065 -0.3048)
			(stroke
				(width 0.1)
				(type default)
			)
			(layer "F.Fab")
		)
		(fp_line
			(start 0.67945 -0.3048)
			(end 0.67945 0.3048)
			(stroke
				(width 0.1)
				(type default)
			)
			(layer "F.Fab")
		)
		(fp_line
			(start 0.67945 0.3048)
			(end 0.120396 0.3048)
			(stroke
				(width 0.1)
				(type default)
			)
			(layer "F.Fab")
		)
		(pad "1" smd circle
			(at -0.40005 0)
			(size 0 0)
			(layers "F.Cu" "F.Mask" "F.Paste")
			(net "P1V8_PCH_AUX_VCC")
		)
		(pad "2" smd circle
			(at 0.40005 0)
			(size 0 0)
			(layers "F.Cu" "F.Mask" "F.Paste")
			(net "GND")
		)
	)
	(footprint ""
		(layer "F.Cu")
		(at 126.396242 -352.812858)
		(property "Reference" "PC1260"
			(at 0 0 0)
			(layer "F.SilkS")
			(hide yes)
			(effects
				(font
					(size 1.27 1.27)
				)
			)
		)
		(property "Value" ""
			(at 0 0 0)
			(layer "F.Fab")
			(effects
				(font
					(size 1.27 1.27)
				)
			)
		)
		(duplicate_pad_numbers_are_jumpers no)
		(fp_line
			(start -1.524 -0.762)
			(end 1.524 -0.762)
			(stroke
				(width 0.1524)
				(type default)
			)
			(layer "F.SilkS")
		)
		(fp_line
			(start -1.524 0.762)
			(end -1.524 -0.762)
			(stroke
				(width 0.1524)
				(type default)
			)
			(layer "F.SilkS")
		)
		(fp_line
			(start 1.524 -0.762)
			(end 1.524 0.762)
			(stroke
				(width 0.1524)
				(type default)
			)
			(layer "F.SilkS")
		)
		(fp_line
			(start 1.524 0.762)
			(end -1.524 0.762)
			(stroke
				(width 0.1524)
				(type default)
			)
			(layer "F.SilkS")
		)
		(fp_line
			(start -1.1049 -0.724916)
			(end -1.1049 0.724916)
			(stroke
				(width 0.1)
				(type default)
			)
			(layer "F.Fab")
		)
		(fp_line
			(start -1.1049 0.724916)
			(end 1.1049 0.724916)
			(stroke
				(width 0.1)
				(type default)
			)
			(layer "F.Fab")
		)
		(fp_line
			(start 1.1049 -0.724916)
			(end -1.1049 -0.724916)
			(stroke
				(width 0.1)
				(type default)
			)
			(layer "F.Fab")
		)
		(fp_line
			(start 1.1049 0.724916)
			(end 1.1049 -0.724916)
			(stroke
				(width 0.1)
				(type default)
			)
			(layer "F.Fab")
		)
		(pad "1" smd rect
			(at -0.889 0 180)
			(size 1.016 1.27)
			(layers "F.Cu" "F.Mask" "F.Paste")
			(net "SW_P12V_PVCCIN_CPU1_FLT")
		)
		(pad "2" smd rect
			(at 0.889 0 180)
			(size 1.016 1.27)
			(layers "F.Cu" "F.Mask" "F.Paste")
			(net "GND")
		)
	)
	(footprint ""
		(layer "F.Cu")
		(at 59.8678 -36.083748 180)
		(property "Reference" "R4065"
			(at 0 0 180)
			(layer "F.SilkS")
			(hide yes)
			(effects
				(font
					(size 1.27 1.27)
				)
			)
		)
		(property "Value" ""
			(at 0 0 180)
			(layer "F.Fab")
			(effects
				(font
					(size 1.27 1.27)
				)
			)
		)
		(duplicate_pad_numbers_are_jumpers no)
		(fp_line
			(start 0.7874 0.4064)
			(end -0.7874 0.4064)
			(stroke
				(width 0.1524)
				(type default)
			)
			(layer "F.SilkS")
		)
		(fp_line
			(start 0.7874 -0.4064)
			(end 0.7874 0.4064)
			(stroke
				(width 0.1524)
				(type default)
			)
			(layer "F.SilkS")
		)
		(fp_line
			(start -0.7874 0.4064)
			(end -0.7874 -0.4064)
			(stroke
				(width 0.1524)
				(type default)
			)
			(layer "F.SilkS")
		)
		(fp_line
			(start -0.7874 -0.4064)
			(end 0.7874 -0.4064)
			(stroke
				(width 0.1524)
				(type default)
			)
			(layer "F.SilkS")
		)
		(fp_line
			(start 0.67945 0.3048)
			(end 0.120396 0.3048)
			(stroke
				(width 0.1)
				(type default)
			)
			(layer "F.Fab")
		)
		(fp_line
			(start 0.67945 -0.3048)
			(end 0.67945 0.3048)
			(stroke
				(width 0.1)
				(type default)
			)
			(layer "F.Fab")
		)
		(fp_line
			(start 0.12065 -0.2794)
			(end 0.12065 -0.3048)
			(stroke
				(width 0.1)
				(type default)
			)
			(layer "F.Fab")
		)
		(fp_line
			(start 0.12065 -0.3048)
			(end 0.67945 -0.3048)
			(stroke
				(width 0.1)
				(type default)
			)
			(layer "F.Fab")
		)
		(fp_line
			(start 0.120396 0.3048)
			(end 0.120396 0.2794)
			(stroke
				(width 0.1)
				(type default)
			)
			(layer "F.Fab")
		)
		(fp_line
			(start 0.120396 0.2794)
			(end -0.12065 0.2794)
			(stroke
				(width 0.1)
				(type default)
			)
			(layer "F.Fab")
		)
		(fp_line
			(start -0.12065 0.3048)
			(end -0.67945 0.3048)
			(stroke
				(width 0.1)
				(type default)
			)
			(layer "F.Fab")
		)
		(fp_line
			(start -0.12065 0.2794)
			(end -0.12065 0.3048)
			(stroke
				(width 0.1)
				(type default)
			)
			(layer "F.Fab")
		)
		(fp_line
			(start -0.12065 -0.2794)
			(end 0.12065 -0.2794)
			(stroke
				(width 0.1)
				(type default)
			)
			(layer "F.Fab")
		)
		(fp_line
			(start -0.12065 -0.305054)
			(end -0.12065 -0.2794)
			(stroke
				(width 0.1)
				(type default)
			)
			(layer "F.Fab")
		)
		(fp_line
			(start -0.67945 0.3048)
			(end -0.67945 -0.305054)
			(stroke
				(width 0.1)
				(type default)
			)
			(layer "F.Fab")
		)
		(fp_line
			(start -0.67945 -0.305054)
			(end -0.12065 -0.305054)
			(stroke
				(width 0.1)
				(type default)
			)
			(layer "F.Fab")
		)
		(pad "1" smd circle
			(at -0.40005 0 180)
			(size 0 0)
			(layers "F.Cu" "F.Mask" "F.Paste")
			(net "P12V_AUX")
		)
		(pad "2" smd circle
			(at 0.40005 0 180)
			(size 0 0)
			(layers "F.Cu" "F.Mask" "F.Paste")
			(net "P12V_OCP_2_EN_G")
		)
	)
	(footprint ""
		(layer "F.Cu")
		(at 369.7224 -74.3458 90)
		(property "Reference" "R4706"
			(at 0 0 90)
			(layer "F.SilkS")
			(hide yes)
			(effects
				(font
					(size 1.27 1.27)
				)
			)
		)
		(property "Value" ""
			(at 0 0 90)
			(layer "F.Fab")
			(effects
				(font
					(size 1.27 1.27)
				)
			)
		)
		(duplicate_pad_numbers_are_jumpers no)
		(fp_line
			(start 0.7874 -0.4064)
			(end 0.7874 0.4064)
			(stroke
				(width 0.1524)
				(type default)
			)
			(layer "F.SilkS")
		)
		(fp_line
			(start -0.7874 -0.4064)
			(end 0.7874 -0.4064)
			(stroke
				(width 0.1524)
				(type default)
			)
			(layer "F.SilkS")
		)
		(fp_line
			(start 0.7874 0.4064)
			(end -0.7874 0.4064)
			(stroke
				(width 0.1524)
				(type default)
			)
			(layer "F.SilkS")
		)
		(fp_line
			(start -0.7874 0.4064)
			(end -0.7874 -0.4064)
			(stroke
				(width 0.1524)
				(type default)
			)
			(layer "F.SilkS")
		)
		(fp_line
			(start -0.12065 -0.305054)
			(end -0.12065 -0.2794)
			(stroke
				(width 0.1)
				(type default)
			)
			(layer "F.Fab")
		)
		(fp_line
			(start -0.67945 -0.305054)
			(end -0.12065 -0.305054)
			(stroke
				(width 0.1)
				(type default)
			)
			(layer "F.Fab")
		)
		(fp_line
			(start 0.67945 -0.3048)
			(end 0.67945 0.3048)
			(stroke
				(width 0.1)
				(type default)
			)
			(layer "F.Fab")
		)
		(fp_line
			(start 0.12065 -0.3048)
			(end 0.67945 -0.3048)
			(stroke
				(width 0.1)
				(type default)
			)
			(layer "F.Fab")
		)
		(fp_line
			(start 0.12065 -0.2794)
			(end 0.12065 -0.3048)
			(stroke
				(width 0.1)
				(type default)
			)
			(layer "F.Fab")
		)
		(fp_line
			(start -0.12065 -0.2794)
			(end 0.12065 -0.2794)
			(stroke
				(width 0.1)
				(type default)
			)
			(layer "F.Fab")
		)
		(fp_line
			(start 0.120396 0.2794)
			(end -0.12065 0.2794)
			(stroke
				(width 0.1)
				(type default)
			)
			(layer "F.Fab")
		)
		(fp_line
			(start -0.12065 0.2794)
			(end -0.12065 0.3048)
			(stroke
				(width 0.1)
				(type default)
			)
			(layer "F.Fab")
		)
		(fp_line
			(start 0.67945 0.3048)
			(end 0.120396 0.3048)
			(stroke
				(width 0.1)
				(type default)
			)
			(layer "F.Fab")
		)
		(fp_line
			(start 0.120396 0.3048)
			(end 0.120396 0.2794)
			(stroke
				(width 0.1)
				(type default)
			)
			(layer "F.Fab")
		)
		(fp_line
			(start -0.12065 0.3048)
			(end -0.67945 0.3048)
			(stroke
				(width 0.1)
				(type default)
			)
			(layer "F.Fab")
		)
		(fp_line
			(start -0.67945 0.3048)
			(end -0.67945 -0.305054)
			(stroke
				(width 0.1)
				(type default)
			)
			(layer "F.Fab")
		)
		(pad "1" smd circle
			(at -0.40005 0 90)
			(size 0 0)
			(layers "F.Cu" "F.Mask" "F.Paste")
			(net "LED_P12V_AUX_R3")
		)
		(pad "2" smd circle
			(at 0.40005 0 90)
			(size 0 0)
			(layers "F.Cu" "F.Mask" "F.Paste")
			(net "P12V_AUX")
		)
	)
	(footprint ""
		(layer "F.Cu")
		(at 479.8695 -468.177372)
		(property "Reference" "JP16_23"
			(at -1.6764 -1.07823 0)
			(unlocked yes)
			(layer "F.SilkS")
			(effects
				(font
					(size 0.7874 0.5842)
					(thickness 0.1524)
				)
				(justify left)
			)
		)
		(property "Value" ""
			(at 0 0 0)
			(layer "F.Fab")
			(effects
				(font
					(size 1.27 1.27)
				)
			)
		)
		(duplicate_pad_numbers_are_jumpers no)
		(pad "1" smd circle
			(at 0 0)
			(size 0.762 0.762)
			(layers "F.Cu" "F.Mask" "F.Paste")
			(net "Net_8623")
		)
	)
	(footprint ""
		(layer "F.Cu")
		(at 191.065404 -32.110426 180)
		(property "Reference" "PD115"
			(at 9.013444 0.703072 0)
			(unlocked yes)
			(layer "F.SilkS")
			(effects
				(font
					(size 0.7874 0.5842)
					(thickness 0.1524)
				)
				(justify left)
			)
		)
		(property "Value" ""
			(at 0 0 180)
			(layer "F.Fab")
			(effects
				(font
					(size 1.27 1.27)
				)
			)
		)
		(duplicate_pad_numbers_are_jumpers no)
		(fp_line
			(start 2.631186 0.999998)
			(end 2.631186 -0.999998)
			(stroke
				(width 0.1524)
				(type default)
			)
			(layer "F.SilkS")
		)
		(fp_line
			(start 2.631186 -0.999998)
			(end -2.250186 -0.999998)
			(stroke
				(width 0.1524)
				(type default)
			)
			(layer "F.SilkS")
		)
		(fp_line
			(start 0.381 -0.0508)
			(end 0.635 -0.0508)
			(stroke
				(width 0.1524)
				(type default)
			)
			(layer "F.SilkS")
		)
		(fp_line
			(start 0.381 -0.0508)
			(end -0.381 0.3302)
			(stroke
				(width 0.1524)
				(type default)
			)
			(layer "F.SilkS")
		)
		(fp_line
			(start 0.381 -0.4318)
			(end 0.381 0.3302)
			(stroke
				(width 0.1524)
				(type default)
			)
			(layer "F.SilkS")
		)
		(fp_line
			(start -0.381 0.3302)
			(end -0.381 -0.4318)
			(stroke
				(width 0.1524)
				(type default)
			)
			(layer "F.SilkS")
		)
		(fp_line
			(start -0.381 -0.0508)
			(end -0.6604 -0.0508)
			(stroke
				(width 0.1524)
				(type default)
			)
			(layer "F.SilkS")
		)
		(fp_line
			(start -0.381 -0.4318)
			(end 0.381 -0.0508)
			(stroke
				(width 0.1524)
				(type default)
			)
			(layer "F.SilkS")
		)
		(fp_line
			(start -2.250186 0.999998)
			(end 2.631186 0.999998)
			(stroke
				(width 0.1524)
				(type default)
			)
			(layer "F.SilkS")
		)
		(fp_line
			(start -2.250186 -0.999998)
			(end -2.250186 0.999998)
			(stroke
				(width 0.1524)
				(type default)
			)
			(layer "F.SilkS")
		)
		(fp_rect
			(start 2.6162 -0.9652)
			(end 2.1844 1.016)
			(stroke
				(width 0)
				(type default)
			)
			(fill yes)
			(layer "F.SilkS")
		)
		(fp_line
			(start 1.450086 0.999998)
			(end 1.450086 -0.999998)
			(stroke
				(width 0.1)
				(type default)
			)
			(layer "F.Fab")
		)
		(fp_line
			(start 1.450086 -0.999998)
			(end -1.450086 -0.999998)
			(stroke
				(width 0.1)
				(type default)
			)
			(layer "F.Fab")
		)
		(fp_line
			(start -1.450086 0.999998)
			(end 1.450086 0.999998)
			(stroke
				(width 0.1)
				(type default)
			)
			(layer "F.Fab")
		)
		(fp_line
			(start -1.450086 -0.999998)
			(end -1.450086 0.999998)
			(stroke
				(width 0.1)
				(type default)
			)
			(layer "F.Fab")
		)
		(fp_text user "-"
			(at 2.4384 -0.22225 180)
			(unlocked yes)
			(layer "F.SilkS")
			(effects
				(font
					(size 1.905 1.4224)
					(thickness 0.1524)
				)
				(justify left)
			)
		)
		(fp_text user "+"
			(at -4.021836 -0.429768 180)
			(unlocked yes)
			(layer "F.SilkS")
			(effects
				(font
					(size 1.905 1.4224)
					(thickness 0.1524)
				)
				(justify left)
			)
		)
		(fp_text user "-"
			(at 2.4384 -0.22225 180)
			(unlocked yes)
			(layer "F.Fab")
			(effects
				(font
					(size 1.905 1.4224)
					(thickness 0.1524)
				)
				(justify left)
			)
		)
		(fp_text user "+"
			(at -3.4798 -0.22225 180)
			(unlocked yes)
			(layer "F.Fab")
			(effects
				(font
					(size 1.905 1.4224)
					(thickness 0.1524)
				)
				(justify left)
			)
		)
		(pad "A" smd rect
			(at -1.450086 0 180)
			(size 1.3208 1.4224)
			(layers "F.Cu" "F.Mask" "F.Paste")
			(net "GND")
		)
		(pad "C" smd rect
			(at 1.450086 0 180)
			(size 1.3208 1.4224)
			(layers "F.Cu" "F.Mask" "F.Paste")
			(net "P12V_AUX")
		)
	)
	(footprint ""
		(layer "F.Cu")
		(at 193.3829 -126.405386)
		(property "Reference" "R4520"
			(at 0 0 0)
			(layer "F.SilkS")
			(hide yes)
			(effects
				(font
					(size 1.27 1.27)
				)
			)
		)
		(property "Value" ""
			(at 0 0 0)
			(layer "F.Fab")
			(effects
				(font
					(size 1.27 1.27)
				)
			)
		)
		(duplicate_pad_numbers_are_jumpers no)
		(fp_line
			(start -0.7874 -0.4064)
			(end 0.7874 -0.4064)
			(stroke
				(width 0.1524)
				(type default)
			)
			(layer "F.SilkS")
		)
		(fp_line
			(start -0.7874 0.4064)
			(end -0.7874 -0.4064)
			(stroke
				(width 0.1524)
				(type default)
			)
			(layer "F.SilkS")
		)
		(fp_line
			(start 0.7874 -0.4064)
			(end 0.7874 0.4064)
			(stroke
				(width 0.1524)
				(type default)
			)
			(layer "F.SilkS")
		)
		(fp_line
			(start 0.7874 0.4064)
			(end -0.7874 0.4064)
			(stroke
				(width 0.1524)
				(type default)
			)
			(layer "F.SilkS")
		)
		(fp_line
			(start -0.67945 -0.305054)
			(end -0.12065 -0.305054)
			(stroke
				(width 0.1)
				(type default)
			)
			(layer "F.Fab")
		)
		(fp_line
			(start -0.67945 0.3048)
			(end -0.67945 -0.305054)
			(stroke
				(width 0.1)
				(type default)
			)
			(layer "F.Fab")
		)
		(fp_line
			(start -0.12065 -0.305054)
			(end -0.12065 -0.2794)
			(stroke
				(width 0.1)
				(type default)
			)
			(layer "F.Fab")
		)
		(fp_line
			(start -0.12065 -0.2794)
			(end 0.12065 -0.2794)
			(stroke
				(width 0.1)
				(type default)
			)
			(layer "F.Fab")
		)
		(fp_line
			(start -0.12065 0.2794)
			(end -0.12065 0.3048)
			(stroke
				(width 0.1)
				(type default)
			)
			(layer "F.Fab")
		)
		(fp_line
			(start -0.12065 0.3048)
			(end -0.67945 0.3048)
			(stroke
				(width 0.1)
				(type default)
			)
			(layer "F.Fab")
		)
		(fp_line
			(start 0.120396 0.2794)
			(end -0.12065 0.2794)
			(stroke
				(width 0.1)
				(type default)
			)
			(layer "F.Fab")
		)
		(fp_line
			(start 0.120396 0.3048)
			(end 0.120396 0.2794)
			(stroke
				(width 0.1)
				(type default)
			)
			(layer "F.Fab")
		)
		(fp_line
			(start 0.12065 -0.3048)
			(end 0.67945 -0.3048)
			(stroke
				(width 0.1)
				(type default)
			)
			(layer "F.Fab")
		)
		(fp_line
			(start 0.12065 -0.2794)
			(end 0.12065 -0.3048)
			(stroke
				(width 0.1)
				(type default)
			)
			(layer "F.Fab")
		)
		(fp_line
			(start 0.67945 -0.3048)
			(end 0.67945 0.3048)
			(stroke
				(width 0.1)
				(type default)
			)
			(layer "F.Fab")
		)
		(fp_line
			(start 0.67945 0.3048)
			(end 0.120396 0.3048)
			(stroke
				(width 0.1)
				(type default)
			)
			(layer "F.Fab")
		)
		(pad "1" smd circle
			(at -0.40005 0)
			(size 0 0)
			(layers "F.Cu" "F.Mask" "F.Paste")
			(net "P3V3")
		)
		(pad "2" smd circle
			(at 0.40005 0)
			(size 0 0)
			(layers "F.Cu" "F.Mask" "F.Paste")
			(net "CLK_SWB_BUF2_OE_N")
		)
	)
)
